# TIMECARD (Time Appliance Project (Time Card)) — schematic netlist excerpt (pin names and nets, part order shuffled) for the footprints in the layout excerpt that follows; sources: Cadence DE-HDL packaged netlist, KiCad conversion of R4006-B0001-02_R01.brd

C104  CAPACITOR  0.1UF 10V 10%  pkg SMC_0402R_H022  page 14 : \1\ = FPGA_MGTAVTT ; \2\ = SG
R145  RESISTOR  33OHM 1%  pkg SMC_0402R_H016  page 16 : \1\ = PCA9546_I2C_SCL ; \2\ = R_PCA9546_I2C_SCL

(kicad_pcb
	(version 20260206)
	(generator "pcbnew")
	(generator_version "10.0")
	(general
		(thickness 1.6)
		(legacy_teardrops no)
	)
	(paper "A4")
	(title_block
		(title "timecard-production-celestica-r4006 — R4006-B0001-02_R01.brd")
		(comment 1 "Time Appliance Project (Time Card) / footprints 940-941 of 1113")
	)
	(layers
		(0 "F.Cu" signal "TOP")
		(4 "In1.Cu" signal "L02_GND1")
		(6 "In2.Cu" signal "L03_SIG1")
		(8 "In3.Cu" signal "L04_GND2")
		(10 "In4.Cu" signal "L05_VCC1")
		(12 "In5.Cu" signal "L06_VCC2")
		(14 "In6.Cu" signal "L07_GND3")
		(16 "In7.Cu" signal "L08_SIG2")
		(18 "In8.Cu" signal "L09_GND4")
		(2 "B.Cu" signal "BOTTOM")
		(9 "F.Adhes" user "F.Adhesive")
		(11 "B.Adhes" user "B.Adhesive")
		(13 "F.Paste" user "Package Geometry/Pastemask Top")
		(15 "B.Paste" user "Package Geometry/Pastemask Bottom")
		(5 "F.SilkS" user "Ref Des/Silkscreen Top")
		(7 "B.SilkS" user "Ref Des/Silkscreen Bottom")
		(1 "F.Mask" user "Board Geometry/Soldermask Top")
		(3 "B.Mask" user "Board Geometry/Soldermask Bottom")
		(17 "Dwgs.User" user "User.Drawings")
		(19 "Cmts.User" user "User.Comments")
		(21 "Eco1.User" user "User.Eco1")
		(23 "Eco2.User" user "User.Eco2")
		(25 "Edge.Cuts" user "Board Geometry/Outline")
		(27 "Margin" user)
		(31 "F.CrtYd" user "Package Geometry/Place Bound Top")
		(29 "B.CrtYd" user "Package Geometry/Place Bound Bottom")
		(35 "F.Fab" user "Ref Des/Assembly Top")
		(33 "B.Fab" user "Ref Des/Assembly Bottom")
	)
	(footprint ""
		(layer "B.Cu")
		(at 17.6784 -39.2176 180)
		(property "Reference" "R145"
			(at 0.4064 -2.55397 0)
			(unlocked yes)
			(layer "B.SilkS")
			(effects
				(font
					(size 0.7874 0.5842)
					(thickness 0.1524)
				)
				(justify mirror)
			)
		)
		(property "Value" "VAL*"
			(at -0.02032 2.13233 180)
			(unlocked yes)
			(layer "B.Fab")
			(hide yes)
			(effects
				(font
					(size 0.7874 0.5842)
					(thickness 0.1524)
				)
				(justify mirror)
			)
		)
		(property "Device Type" "RESISTOR-G155-133R0-01,33OHM,1%"
			(at -0.008382 1.210564 180)
			(unlocked yes)
			(layer "B.Fab")
			(hide yes)
			(effects
				(font
					(size 0.7874 0.5842)
					(thickness 0.1524)
				)
				(justify mirror)
			)
		)
		(property "User Part Number" "PARTNUM*"
			(at -0.02032 4.024884 180)
			(unlocked yes)
			(layer "Cmts.User")
			(hide yes)
			(effects
				(font
					(size 0.7874 0.5842)
					(thickness 0.1524)
				)
				(justify mirror)
			)
		)
		(property "Tolerance" "TOL*"
			(at -0.044704 3.05435 180)
			(unlocked yes)
			(layer "Cmts.User")
			(hide yes)
			(effects
				(font
					(size 0.7874 0.5842)
					(thickness 0.1524)
				)
				(justify mirror)
			)
		)
		(duplicate_pad_numbers_are_jumpers no)
		(fp_line
			(start 1.143 0.5588)
			(end -1.143 0.5588)
			(stroke
				(width 0.1)
				(type default)
			)
			(layer "B.SilkS")
		)
		(fp_line
			(start 1.143 -0.5588)
			(end 1.143 0.5588)
			(stroke
				(width 0.1)
				(type default)
			)
			(layer "B.SilkS")
		)
		(fp_line
			(start -1.143 0.5588)
			(end -1.143 -0.5588)
			(stroke
				(width 0.1)
				(type default)
			)
			(layer "B.SilkS")
		)
		(fp_line
			(start -1.143 -0.5588)
			(end 1.143 -0.5588)
			(stroke
				(width 0.1)
				(type default)
			)
			(layer "B.SilkS")
		)
		(fp_rect
			(start 1.143 0.5588)
			(end -1.143 -0.5588)
			(stroke
				(width 0)
				(type default)
			)
			(fill no)
			(layer "B.CrtYd")
		)
		(fp_line
			(start 0.508 0.3048)
			(end -0.508 0.3048)
			(stroke
				(width 0.1)
				(type default)
			)
			(layer "B.Fab")
		)
		(fp_line
			(start 0.508 -0.3048)
			(end 0.508 0.3048)
			(stroke
				(width 0.1)
				(type default)
			)
			(layer "B.Fab")
		)
		(fp_line
			(start -0.508 0.3048)
			(end -0.508 -0.3048)
			(stroke
				(width 0.1)
				(type default)
			)
			(layer "B.Fab")
		)
		(fp_line
			(start -0.508 -0.3048)
			(end 0.508 -0.3048)
			(stroke
				(width 0.1)
				(type default)
			)
			(layer "B.Fab")
		)
		(pad "1" smd rect
			(at 0.5334 0)
			(size 0.7112 0.6096)
			(layers "B.Cu" "B.Mask" "B.Paste")
			(net "PCA9546_I2C_SCL")
		)
		(pad "2" smd rect
			(at -0.5334 0)
			(size 0.7112 0.6096)
			(layers "B.Cu" "B.Mask" "B.Paste")
			(net "R_PCA9546_I2C_SCL")
		)
		(zone
			(layer "B.Cu")
			(hatch none 0.5)
			(connect_pads
				(clearance 0)
			)
			(min_thickness 0.25)
			(keepout
				(tracks allowed)
				(vias not_allowed)
				(pads allowed)
				(copperpour not_allowed)
				(footprints allowed)
			)
			(placement
				(enabled no)
				(sheetname "")
			)
			(fill
				(thermal_gap 0.5)
				(thermal_bridge_width 0.5)
				(island_removal_mode 0)
			)
			(polygon
				(pts
					(xy 17.6022 -39.5224) (xy 17.6022 -38.9128) (xy 17.7546 -38.9128) (xy 17.7546 -39.5224)
				)
			)
		)
	)
	(footprint ""
		(layer "B.Cu")
		(at 98.17862 -44.323)
		(property "Reference" "C104"
			(at -0.13462 -1.42875 0)
			(unlocked yes)
			(layer "B.SilkS")
			(effects
				(font
					(size 0.635 0.4064)
					(thickness 0.1524)
				)
				(justify mirror)
			)
		)
		(property "Value" "VAL*"
			(at -0.0762 2.067306 0)
			(unlocked yes)
			(layer "B.Fab")
			(hide yes)
			(effects
				(font
					(size 0.7874 0.5842)
					(thickness 0.1524)
				)
				(justify mirror)
			)
		)
		(property "Tolerance" "TOL*"
			(at -0.0762 3.032506 0)
			(unlocked yes)
			(layer "Cmts.User")
			(hide yes)
			(effects
				(font
					(size 0.7874 0.5842)
					(thickness 0.1524)
				)
				(justify mirror)
			)
		)
		(property "User Part Number" "PARTNUM*"
			(at -0.1016 4.023106 0)
			(unlocked yes)
			(layer "Cmts.User")
			(hide yes)
			(effects
				(font
					(size 0.7874 0.5842)
					(thickness 0.1524)
				)
				(justify mirror)
			)
		)
		(property "Device Type" "CAPACITOR-G105-0B104-CK,0.1UF,A"
			(at -0.0508 1.127506 0)
			(unlocked yes)
			(layer "B.Fab")
			(hide yes)
			(effects
				(font
					(size 0.7874 0.5842)
					(thickness 0.1524)
				)
				(justify mirror)
			)
		)
		(duplicate_pad_numbers_are_jumpers no)
		(fp_line
			(start -1.143 -0.5588)
			(end 1.143 -0.5588)
			(stroke
				(width 0.1)
				(type default)
			)
			(layer "B.SilkS")
		)
		(fp_line
			(start -1.143 0.5588)
			(end -1.143 -0.5588)
			(stroke
				(width 0.1)
				(type default)
			)
			(layer "B.SilkS")
		)
		(fp_line
			(start 1.143 -0.5588)
			(end 1.143 0.5588)
			(stroke
				(width 0.1)
				(type default)
			)
			(layer "B.SilkS")
		)
		(fp_line
			(start 1.143 0.5588)
			(end -1.143 0.5588)
			(stroke
				(width 0.1)
				(type default)
			)
			(layer "B.SilkS")
		)
		(fp_rect
			(start -1.143 0.5588)
			(end 1.143 -0.5588)
			(stroke
				(width 0)
				(type default)
			)
			(fill no)
			(layer "B.CrtYd")
		)
		(fp_line
			(start -0.508 -0.3048)
			(end 0.508 -0.3048)
			(stroke
				(width 0.1)
				(type default)
			)
			(layer "B.Fab")
		)
		(fp_line
			(start -0.508 0.3048)
			(end -0.508 -0.3048)
			(stroke
				(width 0.1)
				(type default)
			)
			(layer "B.Fab")
		)
		(fp_line
			(start 0.508 -0.3048)
			(end 0.508 0.3048)
			(stroke
				(width 0.1)
				(type default)
			)
			(layer "B.Fab")
		)
		(fp_line
			(start 0.508 0.3048)
			(end -0.508 0.3048)
			(stroke
				(width 0.1)
				(type default)
			)
			(layer "B.Fab")
		)
		(pad "1" smd rect
			(at 0.5334 0 180)
			(size 0.7112 0.6096)
			(layers "B.Cu" "B.Mask" "B.Paste")
			(net "FPGA_MGTAVTT")
		)
		(pad "2" smd rect
			(at -0.5334 0 180)
			(size 0.7112 0.6096)
			(layers "B.Cu" "B.Mask" "B.Paste")
			(net "SG")
		)
		(zone
			(layer "B.Cu")
			(hatch none 0.5)
			(connect_pads
				(clearance 0)
			)
			(min_thickness 0.25)
			(keepout
				(tracks allowed)
				(vias not_allowed)
				(pads allowed)
				(copperpour not_allowed)
				(footprints allowed)
			)
			(placement
				(enabled no)
				(sheetname "")
			)
			(fill
				(thermal_gap 0.5)
				(thermal_bridge_width 0.5)
				(island_removal_mode 0)
			)
			(polygon
				(pts
					(xy 98.10242 -44.0182) (xy 98.25482 -44.0182) (xy 98.25482 -44.6278) (xy 98.10242 -44.6278)
				)
			)
		)
	)
)
